(kicad_pcb
	(version 20260206)
	(generator "pcbnew")
	(generator_version "10.0")
	(general
		(thickness 1.6)
		(legacy_teardrops no)
	)
	(paper "A4")
	(title_block
		(title "v2-pdb — ms_pdb_v2.brd")
		(comment 1 "Open CloudServer (Microsoft) / footprints 48-56 of 348")
	)
	(layers
		(0 "F.Cu" signal "TOP")
		(4 "In1.Cu" signal "GND")
		(6 "In2.Cu" signal "IN1")
		(8 "In3.Cu" signal "VCC")
		(10 "In4.Cu" signal "VCC1")
		(12 "In5.Cu" signal "IN2")
		(14 "In6.Cu" signal "GND1")
		(2 "B.Cu" signal "BOTTOM")
		(9 "F.Adhes" user "F.Adhesive")
		(11 "B.Adhes" user "B.Adhesive")
		(13 "F.Paste" user "Package Geometry/Pastemask Top")
		(15 "B.Paste" user "Package Geometry/Pastemask Bottom")
		(5 "F.SilkS" user "Ref Des/Silkscreen Top")
		(7 "B.SilkS" user "Ref Des/Silkscreen Bottom")
		(1 "F.Mask" user "Board Geometry/Soldermask Top")
		(3 "B.Mask" user "Board Geometry/Soldermask Bottom")
		(17 "Dwgs.User" user "User.Drawings")
		(19 "Cmts.User" user "User.Comments")
		(21 "Eco1.User" user "User.Eco1")
		(23 "Eco2.User" user "User.Eco2")
		(25 "Edge.Cuts" user "Board Geometry/Outline")
		(27 "Margin" user)
		(31 "F.CrtYd" user "Package Geometry/Place Bound Top")
		(29 "B.CrtYd" user "Package Geometry/Place Bound Bottom")
		(35 "F.Fab" user "Ref Des/Assembly Top")
		(33 "B.Fab" user "Ref Des/Assembly Bottom")
	)
	(footprint ""
		(layer "F.Cu")
		(at 39.458392 -110.374176 90)
		(property "Reference" "R114"
			(at -2.70256 2.149348 90)
			(unlocked yes)
			(layer "F.SilkS")
			(effects
				(font
					(size 0.7874 0.5842)
					(thickness 0.1524)
				)
				(justify left)
			)
		)
		(property "Value" ""
			(at 0 0 90)
			(layer "F.Fab")
			(effects
				(font
					(size 1.27 1.27)
				)
			)
		)
		(duplicate_pad_numbers_are_jumpers no)
		(fp_line
			(start 0.7874 -0.4064)
			(end 0.7874 0.4064)
			(stroke
				(width 0.1524)
				(type default)
			)
			(layer "F.SilkS")
		)
		(fp_line
			(start -0.7874 -0.4064)
			(end 0.7874 -0.4064)
			(stroke
				(width 0.1524)
				(type default)
			)
			(layer "F.SilkS")
		)
		(fp_line
			(start 0.7874 0.4064)
			(end -0.7874 0.4064)
			(stroke
				(width 0.1524)
				(type default)
			)
			(layer "F.SilkS")
		)
		(fp_line
			(start -0.7874 0.4064)
			(end -0.7874 -0.4064)
			(stroke
				(width 0.1524)
				(type default)
			)
			(layer "F.SilkS")
		)
		(fp_poly
			(pts
				(xy -0.508 0.2794) (xy -0.508 0.2286) (xy -0.635 0.2286) (xy -0.635 -0.254) (xy -0.5334 -0.254)
				(xy -0.5334 -0.2794) (xy 0.5334 -0.2794) (xy 0.5334 -0.254) (xy 0.635 -0.254) (xy 0.635 0.254) (xy 0.5334 0.254)
				(xy 0.5334 0.2794)
			)
			(stroke
				(width 0)
				(type default)
			)
			(fill no)
			(layer "F.CrtYd")
		)
		(pad "1" smd rect
			(at 0.40005 0 90)
			(size 0.4572 0.508)
			(layers "F.Cu" "F.Mask" "F.Paste")
			(net "PSU2_REMOTE_P")
		)
		(pad "2" smd rect
			(at -0.40005 0 90)
			(size 0.4572 0.508)
			(layers "F.Cu" "F.Mask" "F.Paste")
			(net "PSU2_REMOTE_R2_P")
		)
	)
	(footprint ""
		(layer "F.Cu")
		(at 22.510496 -446.145158 -90)
		(property "Reference" "R157"
			(at 8.648192 -1.43637 90)
			(unlocked yes)
			(layer "F.SilkS")
			(effects
				(font
					(size 0.7874 0.5842)
					(thickness 0.1524)
				)
				(justify left)
			)
		)
		(property "Value" ""
			(at 0 0 270)
			(layer "F.Fab")
			(effects
				(font
					(size 1.27 1.27)
				)
			)
		)
		(duplicate_pad_numbers_are_jumpers no)
		(fp_line
			(start -0.7874 0.4064)
			(end -0.7874 -0.4064)
			(stroke
				(width 0.1524)
				(type default)
			)
			(layer "F.SilkS")
		)
		(fp_line
			(start 0.7874 0.4064)
			(end -0.7874 0.4064)
			(stroke
				(width 0.1524)
				(type default)
			)
			(layer "F.SilkS")
		)
		(fp_line
			(start -0.7874 -0.4064)
			(end 0.7874 -0.4064)
			(stroke
				(width 0.1524)
				(type default)
			)
			(layer "F.SilkS")
		)
		(fp_line
			(start 0.7874 -0.4064)
			(end 0.7874 0.4064)
			(stroke
				(width 0.1524)
				(type default)
			)
			(layer "F.SilkS")
		)
		(fp_poly
			(pts
				(xy -0.508 0.2794) (xy -0.508 0.2286) (xy -0.635 0.2286) (xy -0.635 -0.254) (xy -0.5334 -0.254)
				(xy -0.5334 -0.2794) (xy 0.5334 -0.2794) (xy 0.5334 -0.254) (xy 0.635 -0.254) (xy 0.635 0.254) (xy 0.5334 0.254)
				(xy 0.5334 0.2794)
			)
			(stroke
				(width 0)
				(type default)
			)
			(fill no)
			(layer "F.CrtYd")
		)
		(pad "1" smd rect
			(at 0.40005 0 270)
			(size 0.4572 0.508)
			(layers "F.Cu" "F.Mask" "F.Paste")
			(net "N42242090")
		)
		(pad "2" smd rect
			(at -0.40005 0 270)
			(size 0.4572 0.508)
			(layers "F.Cu" "F.Mask" "F.Paste")
			(net "GND")
		)
	)
	(footprint ""
		(layer "F.Cu")
		(at 66.891916 -29.351986 180)
		(property "Reference" "R112"
			(at 1.430782 -1.257046 0)
			(unlocked yes)
			(layer "F.SilkS")
			(effects
				(font
					(size 0.7874 0.5842)
					(thickness 0.1524)
				)
				(justify left)
			)
		)
		(property "Value" ""
			(at 0 0 180)
			(layer "F.Fab")
			(effects
				(font
					(size 1.27 1.27)
				)
			)
		)
		(duplicate_pad_numbers_are_jumpers no)
		(fp_line
			(start 0.7874 0.4064)
			(end -0.7874 0.4064)
			(stroke
				(width 0.1524)
				(type default)
			)
			(layer "F.SilkS")
		)
		(fp_line
			(start 0.7874 -0.4064)
			(end 0.7874 0.4064)
			(stroke
				(width 0.1524)
				(type default)
			)
			(layer "F.SilkS")
		)
		(fp_line
			(start -0.7874 0.4064)
			(end -0.7874 -0.4064)
			(stroke
				(width 0.1524)
				(type default)
			)
			(layer "F.SilkS")
		)
		(fp_line
			(start -0.7874 -0.4064)
			(end 0.7874 -0.4064)
			(stroke
				(width 0.1524)
				(type default)
			)
			(layer "F.SilkS")
		)
		(fp_poly
			(pts
				(xy -0.508 0.2794) (xy -0.508 0.2286) (xy -0.635 0.2286) (xy -0.635 -0.254) (xy -0.5334 -0.254)
				(xy -0.5334 -0.2794) (xy 0.5334 -0.2794) (xy 0.5334 -0.254) (xy 0.635 -0.254) (xy 0.635 0.254) (xy 0.5334 0.254)
				(xy 0.5334 0.2794)
			)
			(stroke
				(width 0)
				(type default)
			)
			(fill no)
			(layer "F.CrtYd")
		)
		(pad "1" smd rect
			(at 0.40005 0 180)
			(size 0.4572 0.508)
			(layers "F.Cu" "F.Mask" "F.Paste")
			(net "PSU1_REMOTE_R2_N")
		)
		(pad "2" smd rect
			(at -0.40005 0 180)
			(size 0.4572 0.508)
			(layers "F.Cu" "F.Mask" "F.Paste")
			(net "GND")
		)
	)
	(footprint ""
		(layer "F.Cu")
		(at 27.29357 -280.04389)
		(property "Reference" "R137"
			(at -3.851402 0.175768 0)
			(unlocked yes)
			(layer "F.SilkS")
			(effects
				(font
					(size 0.7874 0.5842)
					(thickness 0.1524)
				)
				(justify left)
			)
		)
		(property "Value" ""
			(at 0 0 0)
			(layer "F.Fab")
			(effects
				(font
					(size 1.27 1.27)
				)
			)
		)
		(duplicate_pad_numbers_are_jumpers no)
		(fp_line
			(start -0.7874 -0.4064)
			(end 0.7874 -0.4064)
			(stroke
				(width 0.1524)
				(type default)
			)
			(layer "F.SilkS")
		)
		(fp_line
			(start -0.7874 0.4064)
			(end -0.7874 -0.4064)
			(stroke
				(width 0.1524)
				(type default)
			)
			(layer "F.SilkS")
		)
		(fp_line
			(start 0.7874 -0.4064)
			(end 0.7874 0.4064)
			(stroke
				(width 0.1524)
				(type default)
			)
			(layer "F.SilkS")
		)
		(fp_line
			(start 0.7874 0.4064)
			(end -0.7874 0.4064)
			(stroke
				(width 0.1524)
				(type default)
			)
			(layer "F.SilkS")
		)
		(fp_poly
			(pts
				(xy -0.508 0.2794) (xy -0.508 0.2286) (xy -0.635 0.2286) (xy -0.635 -0.254) (xy -0.5334 -0.254)
				(xy -0.5334 -0.2794) (xy 0.5334 -0.2794) (xy 0.5334 -0.254) (xy 0.635 -0.254) (xy 0.635 0.254) (xy 0.5334 0.254)
				(xy 0.5334 0.2794)
			)
			(stroke
				(width 0)
				(type default)
			)
			(fill no)
			(layer "F.CrtYd")
		)
		(pad "1" smd rect
			(at 0.40005 0)
			(size 0.4572 0.508)
			(layers "F.Cu" "F.Mask" "F.Paste")
			(net "PSU4_CSAHRE")
		)
		(pad "2" smd rect
			(at -0.40005 0)
			(size 0.4572 0.508)
			(layers "F.Cu" "F.Mask" "F.Paste")
			(net "PSU_CSAHRE")
		)
	)
	(footprint ""
		(layer "F.Cu")
		(at 46.36516 -256.467102 180)
		(property "Reference" "R108"
			(at -1.033272 -0.247396 0)
			(unlocked yes)
			(layer "F.SilkS")
			(effects
				(font
					(size 0.7874 0.5842)
					(thickness 0.1524)
				)
				(justify left)
			)
		)
		(property "Value" ""
			(at 0 0 180)
			(layer "F.Fab")
			(effects
				(font
					(size 1.27 1.27)
				)
			)
		)
		(duplicate_pad_numbers_are_jumpers no)
		(fp_line
			(start 0.7874 0.4064)
			(end -0.7874 0.4064)
			(stroke
				(width 0.1524)
				(type default)
			)
			(layer "F.SilkS")
		)
		(fp_line
			(start 0.7874 -0.4064)
			(end 0.7874 0.4064)
			(stroke
				(width 0.1524)
				(type default)
			)
			(layer "F.SilkS")
		)
		(fp_line
			(start -0.7874 0.4064)
			(end -0.7874 -0.4064)
			(stroke
				(width 0.1524)
				(type default)
			)
			(layer "F.SilkS")
		)
		(fp_line
			(start -0.7874 -0.4064)
			(end 0.7874 -0.4064)
			(stroke
				(width 0.1524)
				(type default)
			)
			(layer "F.SilkS")
		)
		(fp_poly
			(pts
				(xy -0.508 0.2794) (xy -0.508 0.2286) (xy -0.635 0.2286) (xy -0.635 -0.254) (xy -0.5334 -0.254)
				(xy -0.5334 -0.2794) (xy 0.5334 -0.2794) (xy 0.5334 -0.254) (xy 0.635 -0.254) (xy 0.635 0.254) (xy 0.5334 0.254)
				(xy 0.5334 0.2794)
			)
			(stroke
				(width 0)
				(type default)
			)
			(fill no)
			(layer "F.CrtYd")
		)
		(pad "1" smd rect
			(at 0.40005 0 180)
			(size 0.4572 0.508)
			(layers "F.Cu" "F.Mask" "F.Paste")
			(net "PSU4_REMOTE_R_P")
		)
		(pad "2" smd rect
			(at -0.40005 0 180)
			(size 0.4572 0.508)
			(layers "F.Cu" "F.Mask" "F.Paste")
			(net "P12V")
		)
	)
	(footprint ""
		(layer "F.Cu")
		(at 77.999844 -121.19991)
		(property "Reference" "H9"
			(at -9.877298 -3.685032 0)
			(unlocked yes)
			(layer "F.SilkS")
			(effects
				(font
					(size 0.7874 0.5842)
					(thickness 0.1524)
				)
				(justify left)
			)
		)
		(property "Value" ""
			(at 0 0 0)
			(layer "F.Fab")
			(effects
				(font
					(size 1.27 1.27)
				)
			)
		)
		(duplicate_pad_numbers_are_jumpers no)
		(fp_circle
			(center 0 0)
			(end 7.999984 0)
			(stroke
				(width 0.1524)
				(type default)
			)
			(fill no)
			(layer "F.SilkS")
		)
		(fp_arc
			(start 10.063734 10.724134)
			(mid -13.496547 -5.843072)
			(end 14.7066 0)
			(stroke
				(width 0.1524)
				(type default)
			)
			(layer "B.SilkS")
		)
		(fp_arc
			(start 14.7066 0)
			(mid 13.809901 5.056557)
			(end 11.22934 9.496552)
			(stroke
				(width 0.1524)
				(type default)
			)
			(layer "B.SilkS")
		)
		(fp_poly
			(pts
				(arc
					(start 5.0038 0)
					(mid -5.0038 0)
					(end 5.0038 0)
				)
			)
			(stroke
				(width 0)
				(type default)
			)
			(fill no)
			(layer "F.CrtYd")
		)
		(pad "" np_thru_hole circle
			(at 0 0)
			(size 4.0132 4.0132)
			(drill 4.0132)
			(layers "*.Cu" "*.Mask")
			(clearance 0.381)
			(thermal_gap 0.381)
		)
		(pad "2" thru_hole circle
			(at 0 -3.50012)
			(size 0.762 0.762)
			(drill 0.5588)
			(layers "*.Cu" "*.Mask")
			(remove_unused_layers no)
			(net "GND")
			(clearance 0.1524)
			(thermal_gap 0.1524)
		)
		(pad "3" thru_hole circle
			(at -2.500122 -2.500122)
			(size 0.762 0.762)
			(drill 0.5588)
			(layers "*.Cu" "*.Mask")
			(remove_unused_layers no)
			(net "GND")
			(clearance 0.1524)
			(thermal_gap 0.1524)
		)
		(pad "4" thru_hole circle
			(at -3.50012 0)
			(size 0.762 0.762)
			(drill 0.5588)
			(layers "*.Cu" "*.Mask")
			(remove_unused_layers no)
			(net "GND")
			(clearance 0.1524)
			(thermal_gap 0.1524)
		)
		(pad "5" thru_hole circle
			(at -2.500122 2.500122)
			(size 0.762 0.762)
			(drill 0.5588)
			(layers "*.Cu" "*.Mask")
			(remove_unused_layers no)
			(net "GND")
			(clearance 0.1524)
			(thermal_gap 0.1524)
		)
		(pad "6" thru_hole circle
			(at 0 3.50012)
			(size 0.762 0.762)
			(drill 0.5588)
			(layers "*.Cu" "*.Mask")
			(remove_unused_layers no)
			(net "GND")
			(clearance 0.1524)
			(thermal_gap 0.1524)
		)
		(pad "7" thru_hole circle
			(at 2.500122 2.500122)
			(size 0.762 0.762)
			(drill 0.5588)
			(layers "*.Cu" "*.Mask")
			(remove_unused_layers no)
			(net "GND")
			(clearance 0.1524)
			(thermal_gap 0.1524)
		)
		(pad "8" thru_hole circle
			(at 3.50012 0)
			(size 0.762 0.762)
			(drill 0.5588)
			(layers "*.Cu" "*.Mask")
			(remove_unused_layers no)
			(net "GND")
			(clearance 0.1524)
			(thermal_gap 0.1524)
		)
		(pad "9" thru_hole circle
			(at 2.500122 -2.500122)
			(size 0.762 0.762)
			(drill 0.5588)
			(layers "*.Cu" "*.Mask")
			(remove_unused_layers no)
			(net "GND")
			(clearance 0.1524)
			(thermal_gap 0.1524)
		)
		(zone
			(layer "F.Cu")
			(hatch none 0.5)
			(connect_pads
				(clearance 0)
			)
			(min_thickness 0.25)
			(keepout
				(tracks not_allowed)
				(vias allowed)
				(pads allowed)
				(copperpour not_allowed)
				(footprints allowed)
			)
			(placement
				(enabled no)
				(sheetname "")
			)
			(fill
				(thermal_gap 0.5)
				(thermal_bridge_width 0.5)
				(island_removal_mode 0)
			)
			(polygon
				(pts
					(arc
						(start 77.999844 -129.20091)
						(mid 69.998844 -121.19991)
						(end 77.999844 -113.19891)
					)
					(arc
						(start 77.999844 -113.19891)
						(mid 79.434944 -114.63401)
						(end 77.999844 -116.06911)
					)
					(arc
						(start 77.999844 -116.06911)
						(mid 72.869044 -121.19991)
						(end 77.999844 -126.33071)
					)
					(arc
						(start 77.999844 -126.33071)
						(mid 79.434944 -127.76581)
						(end 77.999844 -129.20091)
					)
				)
			)
		)
		(zone
			(layer "F.Cu")
			(hatch none 0.5)
			(connect_pads
				(clearance 0)
			)
			(min_thickness 0.25)
			(keepout
				(tracks not_allowed)
				(vias allowed)
				(pads allowed)
				(copperpour not_allowed)
				(footprints allowed)
			)
			(placement
				(enabled no)
				(sheetname "")
			)
			(fill
				(thermal_gap 0.5)
				(thermal_bridge_width 0.5)
				(island_removal_mode 0)
			)
			(polygon
				(pts
					(arc
						(start 77.999844 -129.20091)
						(mid 86.000844 -121.19991)
						(end 77.999844 -113.19891)
					)
					(arc
						(start 77.999844 -113.19891)
						(mid 76.564744 -114.63401)
						(end 77.999844 -116.06911)
					)
					(arc
						(start 77.999844 -116.06911)
						(mid 83.130644 -121.19991)
						(end 77.999844 -126.33071)
					)
					(arc
						(start 77.999844 -126.33071)
						(mid 76.564744 -127.76581)
						(end 77.999844 -129.20091)
					)
				)
			)
		)
		(zone
			(layers "F.Cu" "B.Cu" "In1.Cu" "In2.Cu" "In3.Cu" "In4.Cu" "In5.Cu" "In6.Cu")
			(hatch none 0.5)
			(connect_pads
				(clearance 0)
			)
			(min_thickness 0.25)
			(keepout
				(tracks not_allowed)
				(vias allowed)
				(pads allowed)
				(copperpour not_allowed)
				(footprints allowed)
			)
			(placement
				(enabled no)
				(sheetname "")
			)
			(fill
				(thermal_gap 0.5)
				(thermal_bridge_width 0.5)
				(island_removal_mode 0)
			)
			(polygon
				(pts
					(arc
						(start 80.511904 -121.19991)
						(mid 75.487784 -121.19991)
						(end 80.511904 -121.19991)
					)
				)
			)
		)
	)
	(footprint ""
		(layer "F.Cu")
		(at 72.81291 -108.56976 -90)
		(property "Reference" "C16"
			(at -2.68224 0.11684 90)
			(unlocked yes)
			(layer "F.SilkS")
			(effects
				(font
					(size 0.7874 0.5842)
					(thickness 0.1524)
				)
				(justify left)
			)
		)
		(property "Value" ""
			(at 0 0 270)
			(layer "F.Fab")
			(effects
				(font
					(size 1.27 1.27)
				)
			)
		)
		(duplicate_pad_numbers_are_jumpers no)
		(fp_line
			(start -0.7874 0.4064)
			(end -0.7874 -0.4064)
			(stroke
				(width 0.1524)
				(type default)
			)
			(layer "F.SilkS")
		)
		(fp_line
			(start 0.7874 0.4064)
			(end -0.7874 0.4064)
			(stroke
				(width 0.1524)
				(type default)
			)
			(layer "F.SilkS")
		)
		(fp_line
			(start 0 0.381)
			(end 0 -0.381)
			(stroke
				(width 0.1524)
				(type default)
			)
			(layer "F.SilkS")
		)
		(fp_line
			(start -0.7874 -0.4064)
			(end 0.7874 -0.4064)
			(stroke
				(width 0.1524)
				(type default)
			)
			(layer "F.SilkS")
		)
		(fp_line
			(start 0.7874 -0.4064)
			(end 0.7874 0.4064)
			(stroke
				(width 0.1524)
				(type default)
			)
			(layer "F.SilkS")
		)
		(fp_poly
			(pts
				(xy -0.5334 0.254) (xy -0.635 0.254) (xy -0.635 0.2286) (xy -0.635 -0.254) (xy -0.5334 -0.254) (xy -0.5334 -0.2794)
				(xy 0.5334 -0.2794) (xy 0.5334 -0.254) (xy 0.635 -0.254) (xy 0.635 0.254) (xy 0.5334 0.254) (xy 0.5334 0.2794)
				(xy -0.508 0.2794) (xy -0.5334 0.2794)
			)
			(stroke
				(width 0)
				(type default)
			)
			(fill no)
			(layer "F.CrtYd")
		)
		(pad "1" smd rect
			(at 0.40005 0 270)
			(size 0.4572 0.508)
			(layers "F.Cu" "F.Mask" "F.Paste")
			(net "P12V")
		)
		(pad "2" smd rect
			(at -0.40005 0 270)
			(size 0.4572 0.508)
			(layers "F.Cu" "F.Mask" "F.Paste")
			(net "GND")
		)
	)
	(footprint ""
		(layer "F.Cu")
		(at 4.059936 -145.974308 -90)
		(property "Reference" "R149"
			(at 1.193292 -1.277366 90)
			(unlocked yes)
			(layer "F.SilkS")
			(effects
				(font
					(size 0.7874 0.5842)
					(thickness 0.1524)
				)
				(justify left)
			)
		)
		(property "Value" ""
			(at 0 0 270)
			(layer "F.Fab")
			(effects
				(font
					(size 1.27 1.27)
				)
			)
		)
		(duplicate_pad_numbers_are_jumpers no)
		(fp_line
			(start -0.7874 0.4064)
			(end -0.7874 -0.4064)
			(stroke
				(width 0.1524)
				(type default)
			)
			(layer "F.SilkS")
		)
		(fp_line
			(start 0.7874 0.4064)
			(end -0.7874 0.4064)
			(stroke
				(width 0.1524)
				(type default)
			)
			(layer "F.SilkS")
		)
		(fp_line
			(start -0.7874 -0.4064)
			(end 0.7874 -0.4064)
			(stroke
				(width 0.1524)
				(type default)
			)
			(layer "F.SilkS")
		)
		(fp_line
			(start 0.7874 -0.4064)
			(end 0.7874 0.4064)
			(stroke
				(width 0.1524)
				(type default)
			)
			(layer "F.SilkS")
		)
		(fp_poly
			(pts
				(xy -0.508 0.2794) (xy -0.508 0.2286) (xy -0.635 0.2286) (xy -0.635 -0.254) (xy -0.5334 -0.254)
				(xy -0.5334 -0.2794) (xy 0.5334 -0.2794) (xy 0.5334 -0.254) (xy 0.635 -0.254) (xy 0.635 0.254) (xy 0.5334 0.254)
				(xy 0.5334 0.2794)
			)
			(stroke
				(width 0)
				(type default)
			)
			(fill no)
			(layer "F.CrtYd")
		)
		(pad "1" smd rect
			(at 0.40005 0 270)
			(size 0.4572 0.508)
			(layers "F.Cu" "F.Mask" "F.Paste")
			(net "N42126764")
		)
		(pad "2" smd rect
			(at -0.40005 0 270)
			(size 0.4572 0.508)
			(layers "F.Cu" "F.Mask" "F.Paste")
			(net "GND")
		)
	)
	(footprint ""
		(layer "F.Cu")
		(at 39.437056 -287.977326 -90)
		(property "Reference" "R106"
			(at -1.168146 -0.000762 90)
			(unlocked yes)
			(layer "F.SilkS")
			(effects
				(font
					(size 0.7874 0.5842)
					(thickness 0.1524)
				)
				(justify left)
			)
		)
		(property "Value" ""
			(at 0 0 270)
			(layer "F.Fab")
			(effects
				(font
					(size 1.27 1.27)
				)
			)
		)
		(duplicate_pad_numbers_are_jumpers no)
		(fp_line
			(start -0.7874 0.4064)
			(end -0.7874 -0.4064)
			(stroke
				(width 0.1524)
				(type default)
			)
			(layer "F.SilkS")
		)
		(fp_line
			(start 0.7874 0.4064)
			(end -0.7874 0.4064)
			(stroke
				(width 0.1524)
				(type default)
			)
			(layer "F.SilkS")
		)
		(fp_line
			(start -0.7874 -0.4064)
			(end 0.7874 -0.4064)
			(stroke
				(width 0.1524)
				(type default)
			)
			(layer "F.SilkS")
		)
		(fp_line
			(start 0.7874 -0.4064)
			(end 0.7874 0.4064)
			(stroke
				(width 0.1524)
				(type default)
			)
			(layer "F.SilkS")
		)
		(fp_poly
			(pts
				(xy -0.508 0.2794) (xy -0.508 0.2286) (xy -0.635 0.2286) (xy -0.635 -0.254) (xy -0.5334 -0.254)
				(xy -0.5334 -0.2794) (xy 0.5334 -0.2794) (xy 0.5334 -0.254) (xy 0.635 -0.254) (xy 0.635 0.254) (xy 0.5334 0.254)
				(xy 0.5334 0.2794)
			)
			(stroke
				(width 0)
				(type default)
			)
			(fill no)
			(layer "F.CrtYd")
		)
		(pad "1" smd rect
			(at 0.40005 0 270)
			(size 0.4572 0.508)
			(layers "F.Cu" "F.Mask" "F.Paste")
			(net "PSU4_REMOTE_P")
		)
		(pad "2" smd rect
			(at -0.40005 0 270)
			(size 0.4572 0.508)
			(layers "F.Cu" "F.Mask" "F.Paste")
			(net "PSU4_REMOTE_R_P")
		)
	)
)
